# S9S_MB_2U (Grand Teton) — schematic netlist excerpt (pin names and nets, part order shuffled) for the footprints in the layout excerpt that follows; sources: Cadence DE-HDL packaged netlist, KiCad conversion of 03242023_DA0F0TMBIJ0_F0T_Motherboard_J_brd_V01_OCP.brd

U237  PI3EQX12902AZLEX  IC  pkg TQFN30_TH_0-4_4-5X2-5  page 166
  VDD1  = P3V3_AUX
  AIP  = P2E_MB_BMC_TX_C_R1_DP<0>
  AIN  = P2E_MB_BMC_TX_C_R1_DN<0>
  GND1  = GND
  \test#\  = PU_TEST
  GND2  = GND
  GND3  = GND
  BON  = P2E_MB_BMC_RX_BUF_C_DN<0>
  BOP  = P2E_MB_BMC_RX_BUF_C_DP<0>
  VDD2  = P3V3_AUX
  \en#\  = FM_P2E_EN_N
  SWB  = FM_P2E_SWB
  GND4  = GND
  FGB  = FM_P2E_FGB
  EQB1  = FM_P2E_EQB1
  VDD3  = P3V3_AUX
  BIP  = P2E_MB_BMC_RX_R1_DP<0>
  BIN  = P2E_MB_BMC_RX_R1_DN<0>
  GND5  = GND
  EQB0  = FM_P2E_EQB0
  EQA0  = FM_P2E_EQA0
  GND6  = GND
  AON  = P2E_MB_BMC_TX_BUF_DN<0>
  AOP  = P2E_MB_BMC_TX_BUF_DP<0>
  VDD4  = P3V3_AUX
  EQA1  = FM_P2E_EQA1
  FGA  = FM_P2E_FGA
  GND7  = GND
  SWA  = FM_P2E_SWA
  MODE  = FM_P2E_MODE
  GND_TH  = GND

(kicad_pcb
	(version 20260206)
	(generator "pcbnew")
	(generator_version "10.0")
	(general
		(thickness 1.6)
		(legacy_teardrops no)
	)
	(paper "A4")
	(title_block
		(title "03242023_DA0F0TMBIJ0_F0T_Motherboard_J_brd_V01_OCP.brd")
		(comment 1 "Grand Teton / footprint 2951 of 6105 (U237), pads 1-31 of 31")
	)
	(layers
		(0 "F.Cu" signal "TOP")
		(4 "In1.Cu" signal "GND")
		(6 "In2.Cu" signal "IN1")
		(8 "In3.Cu" signal "GND1")
		(10 "In4.Cu" signal "IN2")
		(12 "In5.Cu" signal "GND2")
		(14 "In6.Cu" signal "IN3")
		(16 "In7.Cu" signal "GND3")
		(18 "In8.Cu" signal "VCC")
		(20 "In9.Cu" signal "VCC1")
		(22 "In10.Cu" signal "GND4")
		(24 "In11.Cu" signal "IN4")
		(26 "In12.Cu" signal "GND5")
		(28 "In13.Cu" signal "IN5")
		(30 "In14.Cu" signal "GND6")
		(32 "In15.Cu" signal "IN6")
		(34 "In16.Cu" signal "GND7")
		(2 "B.Cu" signal "BOTTOM")
		(9 "F.Adhes" user "F.Adhesive")
		(11 "B.Adhes" user "B.Adhesive")
		(13 "F.Paste" user "Package Geometry/Pastemask Top")
		(15 "B.Paste" user "Package Geometry/Pastemask Bottom")
		(5 "F.SilkS" user "Ref Des/Silkscreen Top")
		(7 "B.SilkS" user "Ref Des/Silkscreen Bottom")
		(1 "F.Mask" user "Board Geometry/Soldermask Top")
		(3 "B.Mask" user "Board Geometry/Soldermask Bottom")
		(17 "Dwgs.User" user "User.Drawings")
		(19 "Cmts.User" user "User.Comments")
		(21 "Eco1.User" user "User.Eco1")
		(23 "Eco2.User" user "User.Eco2")
		(25 "Edge.Cuts" user "Board Geometry/Outline")
		(27 "Margin" user)
		(31 "F.CrtYd" user "Package Geometry/Place Bound Top")
		(29 "B.CrtYd" user "Package Geometry/Place Bound Bottom")
		(35 "F.Fab" user "Ref Des/Assembly Top")
		(33 "B.Fab" user "Ref Des/Assembly Bottom")
	)
	(footprint ""
		(layer "F.Cu")
		(at 21.913596 -390.675876 90)
		(property "Reference" "U237"
			(at -6.036056 -6.165088 0)
			(unlocked yes)
			(layer "F.SilkS")
			(effects
				(font
					(size 0.7874 0.5842)
					(thickness 0.1524)
				)
				(justify left)
			)
		)
		(property "Value" ""
			(at 0 0 90)
			(layer "F.Fab")
			(effects
				(font
					(size 1.27 1.27)
				)
			)
		)
		(duplicate_pad_numbers_are_jumpers no)
		(pad "1" smd circle
			(at -1.249934 -1.800098)
			(size 0 0)
			(layers "F.Cu" "F.Mask" "F.Paste")
			(net "P3V3_AUX")
		)
		(pad "2" smd circle
			(at -1.249934 -1.400048)
			(size 0 0)
			(layers "F.Cu" "F.Mask" "F.Paste")
			(net "P2E_MB_BMC_TX_C_R1_DP<0>")
		)
		(pad "3" smd circle
			(at -1.249934 -0.999998)
			(size 0 0)
			(layers "F.Cu" "F.Mask" "F.Paste")
			(net "P2E_MB_BMC_TX_C_R1_DN<0>")
		)
		(pad "4" smd circle
			(at -1.249934 -0.599948)
			(size 0 0)
			(layers "F.Cu" "F.Mask" "F.Paste")
			(net "GND")
		)
		(pad "5" smd circle
			(at -1.249934 -0.199898)
			(size 0 0)
			(layers "F.Cu" "F.Mask" "F.Paste")
			(net "PU_TEST")
		)
		(pad "6" smd circle
			(at -1.249934 0.199898)
			(size 0 0)
			(layers "F.Cu" "F.Mask" "F.Paste")
			(net "GND")
		)
		(pad "7" smd circle
			(at -1.249934 0.599948)
			(size 0 0)
			(layers "F.Cu" "F.Mask" "F.Paste")
			(net "GND")
		)
		(pad "8" smd circle
			(at -1.249934 0.999998)
			(size 0 0)
			(layers "F.Cu" "F.Mask" "F.Paste")
			(net "P2E_MB_BMC_RX_BUF_C_DN<0>")
		)
		(pad "9" smd circle
			(at -1.249934 1.400048)
			(size 0 0)
			(layers "F.Cu" "F.Mask" "F.Paste")
			(net "P2E_MB_BMC_RX_BUF_C_DP<0>")
		)
		(pad "10" smd circle
			(at -1.249934 1.800098)
			(size 0 0)
			(layers "F.Cu" "F.Mask" "F.Paste")
			(net "P3V3_AUX")
		)
		(pad "11" smd circle
			(at -0.8001 2.249932 90)
			(size 0 0)
			(layers "F.Cu" "F.Mask" "F.Paste")
			(net "FM_P2E_EN_N")
		)
		(pad "12" smd circle
			(at -0.40005 2.249932 90)
			(size 0 0)
			(layers "F.Cu" "F.Mask" "F.Paste")
			(net "FM_P2E_SWB")
		)
		(pad "13" smd circle
			(at 0 2.249932 90)
			(size 0 0)
			(layers "F.Cu" "F.Mask" "F.Paste")
			(net "GND")
		)
		(pad "14" smd circle
			(at 0.40005 2.249932 90)
			(size 0 0)
			(layers "F.Cu" "F.Mask" "F.Paste")
			(net "FM_P2E_FGB")
		)
		(pad "15" smd circle
			(at 0.8001 2.249932 90)
			(size 0 0)
			(layers "F.Cu" "F.Mask" "F.Paste")
			(net "FM_P2E_EQB1")
		)
		(pad "16" smd circle
			(at 1.249934 1.800098 180)
			(size 0 0)
			(layers "F.Cu" "F.Mask" "F.Paste")
			(net "P3V3_AUX")
		)
		(pad "17" smd circle
			(at 1.249934 1.400048 180)
			(size 0 0)
			(layers "F.Cu" "F.Mask" "F.Paste")
			(net "P2E_MB_BMC_RX_R1_DP<0>")
		)
		(pad "18" smd circle
			(at 1.249934 0.999998 180)
			(size 0 0)
			(layers "F.Cu" "F.Mask" "F.Paste")
			(net "P2E_MB_BMC_RX_R1_DN<0>")
		)
		(pad "19" smd circle
			(at 1.249934 0.599948 180)
			(size 0 0)
			(layers "F.Cu" "F.Mask" "F.Paste")
			(net "GND")
		)
		(pad "20" smd circle
			(at 1.249934 0.199898 180)
			(size 0 0)
			(layers "F.Cu" "F.Mask" "F.Paste")
			(net "FM_P2E_EQB0")
		)
		(pad "21" smd circle
			(at 1.249934 -0.199898 180)
			(size 0 0)
			(layers "F.Cu" "F.Mask" "F.Paste")
			(net "FM_P2E_EQA0")
		)
		(pad "22" smd circle
			(at 1.249934 -0.599948 180)
			(size 0 0)
			(layers "F.Cu" "F.Mask" "F.Paste")
			(net "GND")
		)
		(pad "23" smd circle
			(at 1.249934 -0.999998 180)
			(size 0 0)
			(layers "F.Cu" "F.Mask" "F.Paste")
			(net "P2E_MB_BMC_TX_BUF_DN<0>")
		)
		(pad "24" smd circle
			(at 1.249934 -1.400048 180)
			(size 0 0)
			(layers "F.Cu" "F.Mask" "F.Paste")
			(net "P2E_MB_BMC_TX_BUF_DP<0>")
		)
		(pad "25" smd circle
			(at 1.249934 -1.800098 180)
			(size 0 0)
			(layers "F.Cu" "F.Mask" "F.Paste")
			(net "P3V3_AUX")
		)
		(pad "26" smd circle
			(at 0.8001 -2.249932 270)
			(size 0 0)
			(layers "F.Cu" "F.Mask" "F.Paste")
			(net "FM_P2E_EQA1")
		)
		(pad "27" smd circle
			(at 0.40005 -2.249932 270)
			(size 0 0)
			(layers "F.Cu" "F.Mask" "F.Paste")
			(net "FM_P2E_FGA")
		)
		(pad "28" smd circle
			(at 0 -2.249932 270)
			(size 0 0)
			(layers "F.Cu" "F.Mask" "F.Paste")
			(net "GND")
		)
		(pad "29" smd circle
			(at -0.40005 -2.249932 270)
			(size 0 0)
			(layers "F.Cu" "F.Mask" "F.Paste")
			(net "FM_P2E_SWA")
		)
		(pad "30" smd circle
			(at -0.8001 -2.249932 270)
			(size 0 0)
			(layers "F.Cu" "F.Mask" "F.Paste")
			(net "FM_P2E_MODE")
		)
		(pad "TH" smd rect
			(at 0 0 90)
			(size 1.2192 3.2004)
			(layers "F.Cu" "F.Mask" "F.Paste")
			(net "GND")
		)
	)
)
